(kicad_pcb
	(version 20260206)
	(generator "pcbnew")
	(generator_version "10.0")
	(general
		(thickness 1.6)
		(legacy_teardrops no)
	)
	(paper "A4")
	(title_block
		(title "Wiwynn_Tioga_Pass_MB.brd")
		(comment 1 "Tioga Pass / footprints 154-161 of 4770")
	)
	(layers
		(0 "F.Cu" signal "TOP")
		(4 "In1.Cu" signal "L2GND")
		(6 "In2.Cu" signal "L3")
		(8 "In3.Cu" signal "L4GND")
		(10 "In4.Cu" signal "L5")
		(12 "In5.Cu" signal "L6GND")
		(14 "In6.Cu" signal "L7VCC")
		(16 "In7.Cu" signal "L8VCC")
		(18 "In8.Cu" signal "L9GND")
		(20 "In9.Cu" signal "L10")
		(22 "In10.Cu" signal "L11GND")
		(24 "In11.Cu" signal "L12")
		(26 "In12.Cu" signal "L13GND")
		(2 "B.Cu" signal "BOTTOM")
		(9 "F.Adhes" user "F.Adhesive")
		(11 "B.Adhes" user "B.Adhesive")
		(13 "F.Paste" user "Package Geometry/Pastemask Top")
		(15 "B.Paste" user "Package Geometry/Pastemask Bottom")
		(5 "F.SilkS" user "Ref Des/Silkscreen Top")
		(7 "B.SilkS" user "Ref Des/Silkscreen Bottom")
		(1 "F.Mask" user "Board Geometry/Soldermask Top")
		(3 "B.Mask" user "Board Geometry/Soldermask Bottom")
		(17 "Dwgs.User" user "User.Drawings")
		(19 "Cmts.User" user "User.Comments")
		(21 "Eco1.User" user "User.Eco1")
		(23 "Eco2.User" user "User.Eco2")
		(25 "Edge.Cuts" user "Board Geometry/Outline")
		(27 "Margin" user)
		(31 "F.CrtYd" user "Package Geometry/Place Bound Top")
		(29 "B.CrtYd" user "Package Geometry/Place Bound Bottom")
		(35 "F.Fab" user "Ref Des/Assembly Top")
		(33 "B.Fab" user "Ref Des/Assembly Bottom")
	)
	(footprint ""
		(layer "F.Cu")
		(at 408.7495 -109.855 -90)
		(property "Reference" "R2N28"
			(at 0 0 270)
			(layer "F.SilkS")
			(hide yes)
			(effects
				(font
					(size 1.27 1.27)
				)
			)
		)
		(property "Value" ""
			(at 0 0 270)
			(layer "F.Fab")
			(effects
				(font
					(size 1.27 1.27)
				)
			)
		)
		(duplicate_pad_numbers_are_jumpers no)
		(fp_poly
			(pts
				(xy -0.2794 -0.1016) (xy 0.2794 -0.1016) (xy 0.2794 0.9906) (xy -0.2794 0.9906)
			)
			(stroke
				(width 0)
				(type default)
			)
			(fill no)
			(layer "F.CrtYd")
		)
		(fp_line
			(start -0.2794 0.9906)
			(end 0.2794 0.9906)
			(stroke
				(width 0.1)
				(type default)
			)
			(layer "F.Fab")
		)
		(fp_line
			(start 0.2794 0.9906)
			(end 0.2794 -0.1016)
			(stroke
				(width 0.1)
				(type default)
			)
			(layer "F.Fab")
		)
		(fp_line
			(start -0.2794 -0.1016)
			(end -0.2794 0.9906)
			(stroke
				(width 0.1)
				(type default)
			)
			(layer "F.Fab")
		)
		(fp_line
			(start 0.2794 -0.1016)
			(end -0.2794 -0.1016)
			(stroke
				(width 0.1)
				(type default)
			)
			(layer "F.Fab")
		)
		(pad "1" smd rect
			(at 0 0 270)
			(size 0.508 0.508)
			(layers "F.Cu" "F.Mask" "F.Paste")
			(net "P3V3_STBY")
		)
		(pad "2" smd rect
			(at 0 0.889 270)
			(size 0.508 0.508)
			(layers "F.Cu" "F.Mask" "F.Paste")
			(net "FM_PASSWORD_CLEAR_N")
		)
		(zone
			(layer "F.Cu")
			(hatch none 0.5)
			(connect_pads
				(clearance 0)
			)
			(min_thickness 0.25)
			(keepout
				(tracks not_allowed)
				(vias allowed)
				(pads allowed)
				(copperpour not_allowed)
				(footprints allowed)
			)
			(placement
				(enabled no)
				(sheetname "")
			)
			(fill
				(thermal_gap 0.5)
				(thermal_bridge_width 0.5)
				(island_removal_mode 0)
			)
			(polygon
				(pts
					(xy 408.1145 -110.109) (xy 408.1145 -109.601) (xy 408.4955 -109.601) (xy 408.4955 -110.109)
				)
			)
		)
		(zone
			(layer "F.Cu")
			(hatch none 0.5)
			(connect_pads
				(clearance 0)
			)
			(min_thickness 0.25)
			(keepout
				(tracks allowed)
				(vias not_allowed)
				(pads allowed)
				(copperpour not_allowed)
				(footprints allowed)
			)
			(placement
				(enabled no)
				(sheetname "")
			)
			(fill
				(thermal_gap 0.5)
				(thermal_bridge_width 0.5)
				(island_removal_mode 0)
			)
			(polygon
				(pts
					(xy 408.4955 -110.109) (xy 408.4955 -109.601) (xy 408.1145 -109.601) (xy 408.1145 -110.109)
				)
			)
		)
	)
	(footprint ""
		(layer "F.Cu")
		(at 407.8605 -108.204 90)
		(property "Reference" "R8C12"
			(at 0 0 90)
			(layer "F.SilkS")
			(hide yes)
			(effects
				(font
					(size 1.27 1.27)
				)
			)
		)
		(property "Value" ""
			(at 0 0 90)
			(layer "F.Fab")
			(effects
				(font
					(size 1.27 1.27)
				)
			)
		)
		(duplicate_pad_numbers_are_jumpers no)
		(fp_poly
			(pts
				(xy -0.2794 -0.1016) (xy 0.2794 -0.1016) (xy 0.2794 0.9906) (xy -0.2794 0.9906)
			)
			(stroke
				(width 0)
				(type default)
			)
			(fill no)
			(layer "F.CrtYd")
		)
		(fp_line
			(start 0.2794 -0.1016)
			(end -0.2794 -0.1016)
			(stroke
				(width 0.1)
				(type default)
			)
			(layer "F.Fab")
		)
		(fp_line
			(start -0.2794 -0.1016)
			(end -0.2794 0.9906)
			(stroke
				(width 0.1)
				(type default)
			)
			(layer "F.Fab")
		)
		(fp_line
			(start 0.2794 0.9906)
			(end 0.2794 -0.1016)
			(stroke
				(width 0.1)
				(type default)
			)
			(layer "F.Fab")
		)
		(fp_line
			(start -0.2794 0.9906)
			(end 0.2794 0.9906)
			(stroke
				(width 0.1)
				(type default)
			)
			(layer "F.Fab")
		)
		(pad "1" smd rect
			(at 0 0 90)
			(size 0.508 0.508)
			(layers "F.Cu" "F.Mask" "F.Paste")
			(net "SMB_SMLINK0_STBY_LVC3_SCL_R1")
		)
		(pad "2" smd rect
			(at 0 0.889 90)
			(size 0.508 0.508)
			(layers "F.Cu" "F.Mask" "F.Paste")
			(net "SMB_SMLINK0_STBY_LVC3_SCL")
		)
		(zone
			(layer "F.Cu")
			(hatch none 0.5)
			(connect_pads
				(clearance 0)
			)
			(min_thickness 0.25)
			(keepout
				(tracks allowed)
				(vias not_allowed)
				(pads allowed)
				(copperpour not_allowed)
				(footprints allowed)
			)
			(placement
				(enabled no)
				(sheetname "")
			)
			(fill
				(thermal_gap 0.5)
				(thermal_bridge_width 0.5)
				(island_removal_mode 0)
			)
			(polygon
				(pts
					(xy 408.1145 -107.95) (xy 408.1145 -108.458) (xy 408.4955 -108.458) (xy 408.4955 -107.95)
				)
			)
		)
		(zone
			(layer "F.Cu")
			(hatch none 0.5)
			(connect_pads
				(clearance 0)
			)
			(min_thickness 0.25)
			(keepout
				(tracks not_allowed)
				(vias allowed)
				(pads allowed)
				(copperpour not_allowed)
				(footprints allowed)
			)
			(placement
				(enabled no)
				(sheetname "")
			)
			(fill
				(thermal_gap 0.5)
				(thermal_bridge_width 0.5)
				(island_removal_mode 0)
			)
			(polygon
				(pts
					(xy 408.4955 -107.95) (xy 408.4955 -108.458) (xy 408.1145 -108.458) (xy 408.1145 -107.95)
				)
			)
		)
	)
	(footprint ""
		(layer "F.Cu")
		(at 7.333234 -112.123728 90)
		(property "Reference" "C1B18"
			(at 1.47828 0.78994 0)
			(unlocked yes)
			(layer "F.SilkS")
			(effects
				(font
					(size 0.4064 0.254)
					(thickness 0.1524)
				)
			)
		)
		(property "Value" ""
			(at 0 0 90)
			(layer "F.Fab")
			(effects
				(font
					(size 1.27 1.27)
				)
			)
		)
		(duplicate_pad_numbers_are_jumpers no)
		(fp_poly
			(pts
				(xy -0.7239 -0.2159) (xy 0.7239 -0.2159) (xy 0.7239 1.9939) (xy -0.7239 1.9939)
			)
			(stroke
				(width 0)
				(type default)
			)
			(fill no)
			(layer "F.CrtYd")
		)
		(fp_line
			(start 0.7239 -0.2159)
			(end -0.7239 -0.2159)
			(stroke
				(width 0.1)
				(type default)
			)
			(layer "F.Fab")
		)
		(fp_line
			(start -0.7239 -0.2159)
			(end -0.7239 1.9939)
			(stroke
				(width 0.1)
				(type default)
			)
			(layer "F.Fab")
		)
		(fp_line
			(start 0.7239 1.9939)
			(end 0.7239 -0.2159)
			(stroke
				(width 0.1)
				(type default)
			)
			(layer "F.Fab")
		)
		(fp_line
			(start -0.7239 1.9939)
			(end 0.7239 1.9939)
			(stroke
				(width 0.1)
				(type default)
			)
			(layer "F.Fab")
		)
		(pad "1" smd rect
			(at 0 0 90)
			(size 1.27 1.016)
			(layers "F.Cu" "F.Mask" "F.Paste")
			(net "P12V_FAN")
		)
		(pad "2" smd rect
			(at 0 1.778 90)
			(size 1.27 1.016)
			(layers "F.Cu" "F.Mask" "F.Paste")
			(net "GND")
		)
		(zone
			(layer "F.Cu")
			(hatch none 0.5)
			(connect_pads
				(clearance 0)
			)
			(min_thickness 0.25)
			(keepout
				(tracks not_allowed)
				(vias allowed)
				(pads allowed)
				(copperpour not_allowed)
				(footprints allowed)
			)
			(placement
				(enabled no)
				(sheetname "")
			)
			(fill
				(thermal_gap 0.5)
				(thermal_bridge_width 0.5)
				(island_removal_mode 0)
			)
			(polygon
				(pts
					(xy 7.841234 -111.488728) (xy 7.841234 -112.758728) (xy 8.603234 -112.758728) (xy 8.603234 -111.488728)
				)
			)
		)
	)
	(footprint ""
		(layer "F.Cu")
		(at 409.685236 -47.825914 180)
		(property "Reference" "R1T11"
			(at 0 0 180)
			(layer "F.SilkS")
			(hide yes)
			(effects
				(font
					(size 1.27 1.27)
				)
			)
		)
		(property "Value" ""
			(at 0 0 180)
			(layer "F.Fab")
			(effects
				(font
					(size 1.27 1.27)
				)
			)
		)
		(duplicate_pad_numbers_are_jumpers no)
		(fp_poly
			(pts
				(xy -0.2794 -0.1016) (xy 0.2794 -0.1016) (xy 0.2794 0.9906) (xy -0.2794 0.9906)
			)
			(stroke
				(width 0)
				(type default)
			)
			(fill no)
			(layer "F.CrtYd")
		)
		(fp_line
			(start 0.2794 0.9906)
			(end 0.2794 -0.1016)
			(stroke
				(width 0.1)
				(type default)
			)
			(layer "F.Fab")
		)
		(fp_line
			(start 0.2794 -0.1016)
			(end -0.2794 -0.1016)
			(stroke
				(width 0.1)
				(type default)
			)
			(layer "F.Fab")
		)
		(fp_line
			(start -0.2794 0.9906)
			(end 0.2794 0.9906)
			(stroke
				(width 0.1)
				(type default)
			)
			(layer "F.Fab")
		)
		(fp_line
			(start -0.2794 -0.1016)
			(end -0.2794 0.9906)
			(stroke
				(width 0.1)
				(type default)
			)
			(layer "F.Fab")
		)
		(pad "1" smd rect
			(at 0 0 180)
			(size 0.508 0.508)
			(layers "F.Cu" "F.Mask" "F.Paste")
			(net "FM_BOARD_REV_ID2")
		)
		(pad "2" smd rect
			(at 0 0.889 180)
			(size 0.508 0.508)
			(layers "F.Cu" "F.Mask" "F.Paste")
			(net "GND")
		)
	)
	(footprint ""
		(layer "F.Cu")
		(at 442.364876 -13.361924 90)
		(property "Reference" "R2U51"
			(at 0 0 90)
			(layer "F.SilkS")
			(hide yes)
			(effects
				(font
					(size 1.27 1.27)
				)
			)
		)
		(property "Value" ""
			(at 0 0 90)
			(layer "F.Fab")
			(effects
				(font
					(size 1.27 1.27)
				)
			)
		)
		(duplicate_pad_numbers_are_jumpers no)
		(fp_poly
			(pts
				(xy -0.2794 -0.1016) (xy 0.2794 -0.1016) (xy 0.2794 0.9906) (xy -0.2794 0.9906)
			)
			(stroke
				(width 0)
				(type default)
			)
			(fill no)
			(layer "F.CrtYd")
		)
		(fp_line
			(start 0.2794 -0.1016)
			(end -0.2794 -0.1016)
			(stroke
				(width 0.1)
				(type default)
			)
			(layer "F.Fab")
		)
		(fp_line
			(start -0.2794 -0.1016)
			(end -0.2794 0.9906)
			(stroke
				(width 0.1)
				(type default)
			)
			(layer "F.Fab")
		)
		(fp_line
			(start 0.2794 0.9906)
			(end 0.2794 -0.1016)
			(stroke
				(width 0.1)
				(type default)
			)
			(layer "F.Fab")
		)
		(fp_line
			(start -0.2794 0.9906)
			(end 0.2794 0.9906)
			(stroke
				(width 0.1)
				(type default)
			)
			(layer "F.Fab")
		)
		(pad "1" smd rect
			(at 0 0 90)
			(size 0.508 0.508)
			(layers "F.Cu" "F.Mask" "F.Paste")
			(net "H_CPU0_MEMABC_MEMHOT_G_PCH_N")
		)
		(pad "2" smd rect
			(at 0 0.889 90)
			(size 0.508 0.508)
			(layers "F.Cu" "F.Mask" "F.Paste")
			(net "H_CPU0_MEMABC_MEMHOT_G_N")
		)
		(zone
			(layer "F.Cu")
			(hatch none 0.5)
			(connect_pads
				(clearance 0)
			)
			(min_thickness 0.25)
			(keepout
				(tracks allowed)
				(vias not_allowed)
				(pads allowed)
				(copperpour not_allowed)
				(footprints allowed)
			)
			(placement
				(enabled no)
				(sheetname "")
			)
			(fill
				(thermal_gap 0.5)
				(thermal_bridge_width 0.5)
				(island_removal_mode 0)
			)
			(polygon
				(pts
					(xy 442.618876 -13.107924) (xy 442.618876 -13.615924) (xy 442.999876 -13.615924) (xy 442.999876 -13.107924)
				)
			)
		)
		(zone
			(layer "F.Cu")
			(hatch none 0.5)
			(connect_pads
				(clearance 0)
			)
			(min_thickness 0.25)
			(keepout
				(tracks not_allowed)
				(vias allowed)
				(pads allowed)
				(copperpour not_allowed)
				(footprints allowed)
			)
			(placement
				(enabled no)
				(sheetname "")
			)
			(fill
				(thermal_gap 0.5)
				(thermal_bridge_width 0.5)
				(island_removal_mode 0)
			)
			(polygon
				(pts
					(xy 442.999876 -13.107924) (xy 442.999876 -13.615924) (xy 442.618876 -13.615924) (xy 442.618876 -13.107924)
				)
			)
		)
	)
	(footprint ""
		(layer "F.Cu")
		(at 401.066 -49.0855 180)
		(property "Reference" "R7F6"
			(at 0 0 180)
			(layer "F.SilkS")
			(hide yes)
			(effects
				(font
					(size 1.27 1.27)
				)
			)
		)
		(property "Value" ""
			(at 0 0 180)
			(layer "F.Fab")
			(effects
				(font
					(size 1.27 1.27)
				)
			)
		)
		(duplicate_pad_numbers_are_jumpers no)
		(fp_poly
			(pts
				(xy -0.2794 -0.1016) (xy 0.2794 -0.1016) (xy 0.2794 0.9906) (xy -0.2794 0.9906)
			)
			(stroke
				(width 0)
				(type default)
			)
			(fill no)
			(layer "F.CrtYd")
		)
		(fp_line
			(start 0.2794 0.9906)
			(end 0.2794 -0.1016)
			(stroke
				(width 0.1)
				(type default)
			)
			(layer "F.Fab")
		)
		(fp_line
			(start 0.2794 -0.1016)
			(end -0.2794 -0.1016)
			(stroke
				(width 0.1)
				(type default)
			)
			(layer "F.Fab")
		)
		(fp_line
			(start -0.2794 0.9906)
			(end 0.2794 0.9906)
			(stroke
				(width 0.1)
				(type default)
			)
			(layer "F.Fab")
		)
		(fp_line
			(start -0.2794 -0.1016)
			(end -0.2794 0.9906)
			(stroke
				(width 0.1)
				(type default)
			)
			(layer "F.Fab")
		)
		(pad "1" smd rect
			(at 0 0 180)
			(size 0.508 0.508)
			(layers "F.Cu" "F.Mask" "F.Paste")
			(net "P3V3_STBY")
		)
		(pad "2" smd rect
			(at 0 0.889 180)
			(size 0.508 0.508)
			(layers "F.Cu" "F.Mask" "F.Paste")
			(net "PU_SPI0_RST")
		)
		(zone
			(layer "F.Cu")
			(hatch none 0.5)
			(connect_pads
				(clearance 0)
			)
			(min_thickness 0.25)
			(keepout
				(tracks not_allowed)
				(vias allowed)
				(pads allowed)
				(copperpour not_allowed)
				(footprints allowed)
			)
			(placement
				(enabled no)
				(sheetname "")
			)
			(fill
				(thermal_gap 0.5)
				(thermal_bridge_width 0.5)
				(island_removal_mode 0)
			)
			(polygon
				(pts
					(xy 401.32 -49.7205) (xy 400.812 -49.7205) (xy 400.812 -49.3395) (xy 401.32 -49.3395)
				)
			)
		)
		(zone
			(layer "F.Cu")
			(hatch none 0.5)
			(connect_pads
				(clearance 0)
			)
			(min_thickness 0.25)
			(keepout
				(tracks allowed)
				(vias not_allowed)
				(pads allowed)
				(copperpour not_allowed)
				(footprints allowed)
			)
			(placement
				(enabled no)
				(sheetname "")
			)
			(fill
				(thermal_gap 0.5)
				(thermal_bridge_width 0.5)
				(island_removal_mode 0)
			)
			(polygon
				(pts
					(xy 401.32 -49.3395) (xy 400.812 -49.3395) (xy 400.812 -49.7205) (xy 401.32 -49.7205)
				)
			)
		)
	)
	(footprint ""
		(layer "F.Cu")
		(at 170.234102 -57.812686 90)
		(property "Reference" "CT62"
			(at -0.8382 -0.67818 90)
			(unlocked yes)
			(layer "F.SilkS")
			(effects
				(font
					(size 0.4064 0.254)
					(thickness 0.1524)
				)
				(justify left)
			)
		)
		(property "Value" ""
			(at 0 0 90)
			(layer "F.Fab")
			(effects
				(font
					(size 1.27 1.27)
				)
			)
		)
		(duplicate_pad_numbers_are_jumpers no)
		(fp_poly
			(pts
				(xy 0.3048 -0.1016) (xy 0.3048 0.9906) (xy -0.3048 0.9906) (xy -0.3048 -0.1016)
			)
			(stroke
				(width 0)
				(type default)
			)
			(fill no)
			(layer "F.CrtYd")
		)
		(fp_line
			(start 0.3048 -0.1016)
			(end -0.3048 -0.1016)
			(stroke
				(width 0.1)
				(type default)
			)
			(layer "F.Fab")
		)
		(fp_line
			(start -0.3048 -0.1016)
			(end -0.3048 0.9906)
			(stroke
				(width 0.1)
				(type default)
			)
			(layer "F.Fab")
		)
		(fp_line
			(start 0.3048 0.9906)
			(end 0.3048 -0.1016)
			(stroke
				(width 0.1)
				(type default)
			)
			(layer "F.Fab")
		)
		(fp_line
			(start -0.3048 0.9906)
			(end 0.3048 0.9906)
			(stroke
				(width 0.1)
				(type default)
			)
			(layer "F.Fab")
		)
		(pad "1" smd rect
			(at 0 0 90)
			(size 0.508 0.508)
			(layers "F.Cu" "F.Mask" "F.Paste")
			(net "VR_PVCCIO_CPU1_PH1_SW")
		)
		(pad "2" smd rect
			(at 0 0.889 90)
			(size 0.508 0.508)
			(layers "F.Cu" "F.Mask" "F.Paste")
			(net "VR_PVCCIO_CPU1_PH1_SW_RC")
		)
		(zone
			(layer "F.Cu")
			(hatch none 0.5)
			(connect_pads
				(clearance 0)
			)
			(min_thickness 0.25)
			(keepout
				(tracks allowed)
				(vias not_allowed)
				(pads allowed)
				(copperpour not_allowed)
				(footprints allowed)
			)
			(placement
				(enabled no)
				(sheetname "")
			)
			(fill
				(thermal_gap 0.5)
				(thermal_bridge_width 0.5)
				(island_removal_mode 0)
			)
			(polygon
				(pts
					(xy 170.488102 -57.558686) (xy 170.488102 -58.066686) (xy 170.869102 -58.066686) (xy 170.869102 -57.558686)
				)
			)
		)
		(zone
			(layer "F.Cu")
			(hatch none 0.5)
			(connect_pads
				(clearance 0)
			)
			(min_thickness 0.25)
			(keepout
				(tracks not_allowed)
				(vias allowed)
				(pads allowed)
				(copperpour not_allowed)
				(footprints allowed)
			)
			(placement
				(enabled no)
				(sheetname "")
			)
			(fill
				(thermal_gap 0.5)
				(thermal_bridge_width 0.5)
				(island_removal_mode 0)
			)
			(polygon
				(pts
					(xy 170.869102 -57.558686) (xy 170.869102 -58.066686) (xy 170.488102 -58.066686) (xy 170.488102 -57.558686)
				)
			)
		)
	)
	(footprint ""
		(layer "F.Cu")
		(at 44.1198 -52.79898 -90)
		(property "Reference" "R1E3"
			(at 0 0 270)
			(layer "F.SilkS")
			(hide yes)
			(effects
				(font
					(size 1.27 1.27)
				)
			)
		)
		(property "Value" ""
			(at 0 0 270)
			(layer "F.Fab")
			(effects
				(font
					(size 1.27 1.27)
				)
			)
		)
		(duplicate_pad_numbers_are_jumpers no)
		(fp_poly
			(pts
				(xy -0.4953 -0.2032) (xy 0.4953 -0.2032) (xy 0.4953 1.6002) (xy -0.4953 1.6002)
			)
			(stroke
				(width 0)
				(type default)
			)
			(fill no)
			(layer "F.CrtYd")
		)
		(fp_line
			(start -0.4953 1.6002)
			(end -0.4953 -0.2032)
			(stroke
				(width 0.1)
				(type default)
			)
			(layer "F.Fab")
		)
		(fp_line
			(start 0.4953 1.6002)
			(end -0.4953 1.6002)
			(stroke
				(width 0.1)
				(type default)
			)
			(layer "F.Fab")
		)
		(fp_line
			(start -0.4953 -0.2032)
			(end 0.4953 -0.2032)
			(stroke
				(width 0.1)
				(type default)
			)
			(layer "F.Fab")
		)
		(fp_line
			(start 0.4953 -0.2032)
			(end 0.4953 1.6002)
			(stroke
				(width 0.1)
				(type default)
			)
			(layer "F.Fab")
		)
		(pad "1" smd rect
			(at 0 0 270)
			(size 0.762 0.889)
			(layers "F.Cu" "F.Mask" "F.Paste")
			(net "PVCCIN_CPU1")
		)
		(pad "2" smd rect
			(at 0 1.397 270)
			(size 0.762 0.889)
			(layers "F.Cu" "F.Mask" "F.Paste")
			(net "GND")
		)
		(zone
			(layer "F.Cu")
			(hatch none 0.5)
			(connect_pads
				(clearance 0)
			)
			(min_thickness 0.25)
			(keepout
				(tracks not_allowed)
				(vias allowed)
				(pads allowed)
				(copperpour not_allowed)
				(footprints allowed)
			)
			(placement
				(enabled no)
				(sheetname "")
			)
			(fill
				(thermal_gap 0.5)
				(thermal_bridge_width 0.5)
				(island_removal_mode 0)
			)
			(polygon
				(pts
					(xy 43.1673 -53.17998) (xy 43.1673 -52.41798) (xy 43.6753 -52.41798) (xy 43.6753 -53.17998)
				)
			)
		)
		(zone
			(layer "F.Cu")
			(hatch none 0.5)
			(connect_pads
				(clearance 0)
			)
			(min_thickness 0.25)
			(keepout
				(tracks allowed)
				(vias not_allowed)
				(pads allowed)
				(copperpour not_allowed)
				(footprints allowed)
			)
			(placement
				(enabled no)
				(sheetname "")
			)
			(fill
				(thermal_gap 0.5)
				(thermal_bridge_width 0.5)
				(island_removal_mode 0)
			)
			(polygon
				(pts
					(xy 43.1673 -52.41798) (xy 43.6753 -52.41798) (xy 43.6753 -53.17998) (xy 43.1673 -53.17998)
				)
			)
		)
	)
)
